# T6G (Grand Teton) — schematic netlist excerpt (pin names and nets, part order shuffled) for the footprints in the layout excerpt that follows; sources: Cadence DE-HDL packaged netlist, KiCad conversion of 04192023_DAF0TMB3IC0_F0TG_MB_C_brd_V02_OCP.brd

C483  Q_CAP  4.7UF 6.3V 20% X6S  pkg 0402  page 356 : A = P0V9_CPU1_RT3_2A ; B = GND
R3114  Q_RES  33.2 1% CHIP  pkg 0402LF  page 240 : A = SMB_FAN_3V3AUX_SDA ; B = SMB_FAN_3V3AUX_R_SDA

(kicad_pcb
	(version 20260206)
	(generator "pcbnew")
	(generator_version "10.0")
	(general
		(thickness 1.6)
		(legacy_teardrops no)
	)
	(paper "A4")
	(title_block
		(title "04192023_DAF0TMB3IC0_F0TG_MB_C_brd_V02_OCP.brd")
		(comment 1 "Grand Teton / footprints 6380-6381 of 8354")
	)
	(layers
		(0 "F.Cu" signal "TOP")
		(4 "In1.Cu" signal "GND")
		(6 "In2.Cu" signal "IN1")
		(8 "In3.Cu" signal "GND1")
		(10 "In4.Cu" signal "IN2")
		(12 "In5.Cu" signal "GND2")
		(14 "In6.Cu" signal "IN3")
		(16 "In7.Cu" signal "GND3")
		(18 "In8.Cu" signal "VCC")
		(20 "In9.Cu" signal "VCC1")
		(22 "In10.Cu" signal "GND4")
		(24 "In11.Cu" signal "IN4")
		(26 "In12.Cu" signal "GND5")
		(28 "In13.Cu" signal "IN5")
		(30 "In14.Cu" signal "GND6")
		(32 "In15.Cu" signal "IN6")
		(34 "In16.Cu" signal "GND7")
		(2 "B.Cu" signal "BOTTOM")
		(9 "F.Adhes" user "F.Adhesive")
		(11 "B.Adhes" user "B.Adhesive")
		(13 "F.Paste" user "Package Geometry/Pastemask Top")
		(15 "B.Paste" user "Package Geometry/Pastemask Bottom")
		(5 "F.SilkS" user "Ref Des/Silkscreen Top")
		(7 "B.SilkS" user "Ref Des/Silkscreen Bottom")
		(1 "F.Mask" user "Board Geometry/Soldermask Top")
		(3 "B.Mask" user "Board Geometry/Soldermask Bottom")
		(17 "Dwgs.User" user "User.Drawings")
		(19 "Cmts.User" user "User.Comments")
		(21 "Eco1.User" user "User.Eco1")
		(23 "Eco2.User" user "User.Eco2")
		(25 "Edge.Cuts" user "Board Geometry/Outline")
		(27 "Margin" user)
		(31 "F.CrtYd" user "Package Geometry/Place Bound Top")
		(29 "B.CrtYd" user "Package Geometry/Place Bound Bottom")
		(35 "F.Fab" user "Ref Des/Assembly Top")
		(33 "B.Fab" user "Ref Des/Assembly Bottom")
	)
	(footprint ""
		(layer "B.Cu")
		(at 157.989778 -17.969992 -90)
		(property "Reference" "R3114"
			(at 0 0 90)
			(layer "B.SilkS")
			(hide yes)
			(effects
				(font
					(size 1.27 1.27)
				)
				(justify mirror)
			)
		)
		(property "Value" ""
			(at 0 0 90)
			(layer "B.Fab")
			(effects
				(font
					(size 1.27 1.27)
				)
				(justify mirror)
			)
		)
		(duplicate_pad_numbers_are_jumpers no)
		(fp_line
			(start -0.7874 0.4064)
			(end 0.7874 0.4064)
			(stroke
				(width 0.1524)
				(type default)
			)
			(layer "B.SilkS")
		)
		(fp_line
			(start 0.7874 0.4064)
			(end 0.7874 -0.4064)
			(stroke
				(width 0.1524)
				(type default)
			)
			(layer "B.SilkS")
		)
		(fp_line
			(start -0.7874 -0.4064)
			(end -0.7874 0.4064)
			(stroke
				(width 0.1524)
				(type default)
			)
			(layer "B.SilkS")
		)
		(fp_line
			(start 0.7874 -0.4064)
			(end -0.7874 -0.4064)
			(stroke
				(width 0.1524)
				(type default)
			)
			(layer "B.SilkS")
		)
		(fp_line
			(start -0.67945 0.3048)
			(end -0.120396 0.3048)
			(stroke
				(width 0.1)
				(type default)
			)
			(layer "B.Fab")
		)
		(fp_line
			(start -0.120396 0.3048)
			(end -0.120396 0.2794)
			(stroke
				(width 0.1)
				(type default)
			)
			(layer "B.Fab")
		)
		(fp_line
			(start 0.12065 0.3048)
			(end 0.67945 0.3048)
			(stroke
				(width 0.1)
				(type default)
			)
			(layer "B.Fab")
		)
		(fp_line
			(start 0.67945 0.3048)
			(end 0.67945 -0.305054)
			(stroke
				(width 0.1)
				(type default)
			)
			(layer "B.Fab")
		)
		(fp_line
			(start -0.120396 0.2794)
			(end 0.12065 0.2794)
			(stroke
				(width 0.1)
				(type default)
			)
			(layer "B.Fab")
		)
		(fp_line
			(start 0.12065 0.2794)
			(end 0.12065 0.3048)
			(stroke
				(width 0.1)
				(type default)
			)
			(layer "B.Fab")
		)
		(fp_line
			(start -0.12065 -0.2794)
			(end -0.12065 -0.3048)
			(stroke
				(width 0.1)
				(type default)
			)
			(layer "B.Fab")
		)
		(fp_line
			(start 0.12065 -0.2794)
			(end -0.12065 -0.2794)
			(stroke
				(width 0.1)
				(type default)
			)
			(layer "B.Fab")
		)
		(fp_line
			(start -0.67945 -0.3048)
			(end -0.67945 0.3048)
			(stroke
				(width 0.1)
				(type default)
			)
			(layer "B.Fab")
		)
		(fp_line
			(start -0.12065 -0.3048)
			(end -0.67945 -0.3048)
			(stroke
				(width 0.1)
				(type default)
			)
			(layer "B.Fab")
		)
		(fp_line
			(start 0.12065 -0.305054)
			(end 0.12065 -0.2794)
			(stroke
				(width 0.1)
				(type default)
			)
			(layer "B.Fab")
		)
		(fp_line
			(start 0.67945 -0.305054)
			(end 0.12065 -0.305054)
			(stroke
				(width 0.1)
				(type default)
			)
			(layer "B.Fab")
		)
		(pad "1" smd circle
			(at 0.40005 0 90)
			(size 0 0)
			(layers "B.Cu" "B.Mask" "B.Paste")
			(net "SMB_FAN_3V3AUX_SDA")
		)
		(pad "2" smd circle
			(at -0.40005 0 90)
			(size 0 0)
			(layers "B.Cu" "B.Mask" "B.Paste")
			(net "SMB_FAN_3V3AUX_R_SDA")
		)
	)
	(footprint ""
		(layer "B.Cu")
		(at 127.691134 -390.560052 90)
		(property "Reference" "C483"
			(at 0 0 90)
			(layer "B.SilkS")
			(hide yes)
			(effects
				(font
					(size 1.27 1.27)
				)
				(justify mirror)
			)
		)
		(property "Value" ""
			(at 0 0 90)
			(layer "B.Fab")
			(effects
				(font
					(size 1.27 1.27)
				)
				(justify mirror)
			)
		)
		(duplicate_pad_numbers_are_jumpers no)
		(fp_line
			(start 0.7874 -0.4064)
			(end -0.7874 -0.4064)
			(stroke
				(width 0.1524)
				(type default)
			)
			(layer "B.SilkS")
		)
		(fp_line
			(start -0.7874 -0.4064)
			(end -0.7874 0.4064)
			(stroke
				(width 0.1524)
				(type default)
			)
			(layer "B.SilkS")
		)
		(fp_line
			(start 0.7874 0.4064)
			(end 0.7874 -0.4064)
			(stroke
				(width 0.1524)
				(type default)
			)
			(layer "B.SilkS")
		)
		(fp_line
			(start -0.7874 0.4064)
			(end 0.7874 0.4064)
			(stroke
				(width 0.1524)
				(type default)
			)
			(layer "B.SilkS")
		)
		(fp_line
			(start 0.67945 -0.305054)
			(end 0.12065 -0.305054)
			(stroke
				(width 0.1)
				(type default)
			)
			(layer "B.Fab")
		)
		(fp_line
			(start 0.12065 -0.305054)
			(end 0.12065 -0.2794)
			(stroke
				(width 0.1)
				(type default)
			)
			(layer "B.Fab")
		)
		(fp_line
			(start -0.12065 -0.3048)
			(end -0.67945 -0.3048)
			(stroke
				(width 0.1)
				(type default)
			)
			(layer "B.Fab")
		)
		(fp_line
			(start -0.67945 -0.3048)
			(end -0.67945 0.3048)
			(stroke
				(width 0.1)
				(type default)
			)
			(layer "B.Fab")
		)
		(fp_line
			(start 0.12065 -0.2794)
			(end -0.12065 -0.2794)
			(stroke
				(width 0.1)
				(type default)
			)
			(layer "B.Fab")
		)
		(fp_line
			(start -0.12065 -0.2794)
			(end -0.12065 -0.3048)
			(stroke
				(width 0.1)
				(type default)
			)
			(layer "B.Fab")
		)
		(fp_line
			(start 0.12065 0.2794)
			(end 0.12065 0.3048)
			(stroke
				(width 0.1)
				(type default)
			)
			(layer "B.Fab")
		)
		(fp_line
			(start -0.120396 0.2794)
			(end 0.12065 0.2794)
			(stroke
				(width 0.1)
				(type default)
			)
			(layer "B.Fab")
		)
		(fp_line
			(start 0.67945 0.3048)
			(end 0.67945 -0.305054)
			(stroke
				(width 0.1)
				(type default)
			)
			(layer "B.Fab")
		)
		(fp_line
			(start 0.12065 0.3048)
			(end 0.67945 0.3048)
			(stroke
				(width 0.1)
				(type default)
			)
			(layer "B.Fab")
		)
		(fp_line
			(start -0.120396 0.3048)
			(end -0.120396 0.2794)
			(stroke
				(width 0.1)
				(type default)
			)
			(layer "B.Fab")
		)
		(fp_line
			(start -0.67945 0.3048)
			(end -0.120396 0.3048)
			(stroke
				(width 0.1)
				(type default)
			)
			(layer "B.Fab")
		)
		(pad "1" smd circle
			(at 0.40005 0 270)
			(size 0 0)
			(layers "B.Cu" "B.Mask" "B.Paste")
			(net "P0V9_CPU1_RT3_2A")
		)
		(pad "2" smd circle
			(at -0.40005 0 270)
			(size 0 0)
			(layers "B.Cu" "B.Mask" "B.Paste")
			(net "GND")
		)
	)
)
